# S9S_MB_2U (Grand Teton) — schematic netlist excerpt (pin names and nets, part order shuffled) for the footprints in the layout excerpt that follows; sources: Cadence DE-HDL packaged netlist, KiCad conversion of 03242023_DA0F0TMBIJ0_F0T_Motherboard_J_brd_V01_OCP.brd

R268  Q_RES  240 1% EMPTY  pkg 0402LF  page 119 : A = PVNN_TERM_CPU1 ; B = PU_CPU1_LEGACY_SKT
C2320  Q_CAP  0.1UF 25V 10% EMPTY  pkg 0402  page 196 : A = P3V3_AUX_USB_HUB_2 ; B = GND
PC542_P1_3  Q_CAP  22UF 4V 20% X6S  pkg C0805  page 286 : A = PVCCIN_CPU1 ; B = GND

(kicad_pcb
	(version 20260206)
	(generator "pcbnew")
	(generator_version "10.0")
	(general
		(thickness 1.6)
		(legacy_teardrops no)
	)
	(paper "A4")
	(title_block
		(title "03242023_DA0F0TMBIJ0_F0T_Motherboard_J_brd_V01_OCP.brd")
		(comment 1 "Grand Teton / footprints 5603-5605 of 6105")
	)
	(layers
		(0 "F.Cu" signal "TOP")
		(4 "In1.Cu" signal "GND")
		(6 "In2.Cu" signal "IN1")
		(8 "In3.Cu" signal "GND1")
		(10 "In4.Cu" signal "IN2")
		(12 "In5.Cu" signal "GND2")
		(14 "In6.Cu" signal "IN3")
		(16 "In7.Cu" signal "GND3")
		(18 "In8.Cu" signal "VCC")
		(20 "In9.Cu" signal "VCC1")
		(22 "In10.Cu" signal "GND4")
		(24 "In11.Cu" signal "IN4")
		(26 "In12.Cu" signal "GND5")
		(28 "In13.Cu" signal "IN5")
		(30 "In14.Cu" signal "GND6")
		(32 "In15.Cu" signal "IN6")
		(34 "In16.Cu" signal "GND7")
		(2 "B.Cu" signal "BOTTOM")
		(9 "F.Adhes" user "F.Adhesive")
		(11 "B.Adhes" user "B.Adhesive")
		(13 "F.Paste" user "Package Geometry/Pastemask Top")
		(15 "B.Paste" user "Package Geometry/Pastemask Bottom")
		(5 "F.SilkS" user "Ref Des/Silkscreen Top")
		(7 "B.SilkS" user "Ref Des/Silkscreen Bottom")
		(1 "F.Mask" user "Board Geometry/Soldermask Top")
		(3 "B.Mask" user "Board Geometry/Soldermask Bottom")
		(17 "Dwgs.User" user "User.Drawings")
		(19 "Cmts.User" user "User.Comments")
		(21 "Eco1.User" user "User.Eco1")
		(23 "Eco2.User" user "User.Eco2")
		(25 "Edge.Cuts" user "Board Geometry/Outline")
		(27 "Margin" user)
		(31 "F.CrtYd" user "Package Geometry/Place Bound Top")
		(29 "B.CrtYd" user "Package Geometry/Place Bound Bottom")
		(35 "F.Fab" user "Ref Des/Assembly Top")
		(33 "B.Fab" user "Ref Des/Assembly Bottom")
	)
	(footprint ""
		(layer "B.Cu")
		(at 175.273208 -198.114158)
		(property "Reference" "R268"
			(at 0 0 0)
			(layer "B.SilkS")
			(hide yes)
			(effects
				(font
					(size 1.27 1.27)
				)
				(justify mirror)
			)
		)
		(property "Value" ""
			(at 0 0 0)
			(layer "B.Fab")
			(effects
				(font
					(size 1.27 1.27)
				)
				(justify mirror)
			)
		)
		(duplicate_pad_numbers_are_jumpers no)
		(fp_line
			(start -0.7874 -0.4064)
			(end -0.7874 0.4064)
			(stroke
				(width 0.1524)
				(type default)
			)
			(layer "B.SilkS")
		)
		(fp_line
			(start -0.7874 0.4064)
			(end 0.7874 0.4064)
			(stroke
				(width 0.1524)
				(type default)
			)
			(layer "B.SilkS")
		)
		(fp_line
			(start 0.7874 -0.4064)
			(end -0.7874 -0.4064)
			(stroke
				(width 0.1524)
				(type default)
			)
			(layer "B.SilkS")
		)
		(fp_line
			(start 0.7874 0.4064)
			(end 0.7874 -0.4064)
			(stroke
				(width 0.1524)
				(type default)
			)
			(layer "B.SilkS")
		)
		(fp_line
			(start -0.67945 -0.3048)
			(end -0.67945 0.3048)
			(stroke
				(width 0.1)
				(type default)
			)
			(layer "B.Fab")
		)
		(fp_line
			(start -0.67945 0.3048)
			(end -0.120396 0.3048)
			(stroke
				(width 0.1)
				(type default)
			)
			(layer "B.Fab")
		)
		(fp_line
			(start -0.12065 -0.3048)
			(end -0.67945 -0.3048)
			(stroke
				(width 0.1)
				(type default)
			)
			(layer "B.Fab")
		)
		(fp_line
			(start -0.12065 -0.2794)
			(end -0.12065 -0.3048)
			(stroke
				(width 0.1)
				(type default)
			)
			(layer "B.Fab")
		)
		(fp_line
			(start -0.120396 0.2794)
			(end 0.12065 0.2794)
			(stroke
				(width 0.1)
				(type default)
			)
			(layer "B.Fab")
		)
		(fp_line
			(start -0.120396 0.3048)
			(end -0.120396 0.2794)
			(stroke
				(width 0.1)
				(type default)
			)
			(layer "B.Fab")
		)
		(fp_line
			(start 0.12065 -0.305054)
			(end 0.12065 -0.2794)
			(stroke
				(width 0.1)
				(type default)
			)
			(layer "B.Fab")
		)
		(fp_line
			(start 0.12065 -0.2794)
			(end -0.12065 -0.2794)
			(stroke
				(width 0.1)
				(type default)
			)
			(layer "B.Fab")
		)
		(fp_line
			(start 0.12065 0.2794)
			(end 0.12065 0.3048)
			(stroke
				(width 0.1)
				(type default)
			)
			(layer "B.Fab")
		)
		(fp_line
			(start 0.12065 0.3048)
			(end 0.67945 0.3048)
			(stroke
				(width 0.1)
				(type default)
			)
			(layer "B.Fab")
		)
		(fp_line
			(start 0.67945 -0.305054)
			(end 0.12065 -0.305054)
			(stroke
				(width 0.1)
				(type default)
			)
			(layer "B.Fab")
		)
		(fp_line
			(start 0.67945 0.3048)
			(end 0.67945 -0.305054)
			(stroke
				(width 0.1)
				(type default)
			)
			(layer "B.Fab")
		)
		(pad "1" smd circle
			(at 0.40005 0 180)
			(size 0 0)
			(layers "B.Cu" "B.Mask" "B.Paste")
			(net "PVNN_TERM_CPU1")
		)
		(pad "2" smd circle
			(at -0.40005 0 180)
			(size 0 0)
			(layers "B.Cu" "B.Mask" "B.Paste")
			(net "PU_CPU1_LEGACY_SKT")
		)
	)
	(footprint ""
		(layer "B.Cu")
		(at 117.529102 -324.792086 -90)
		(property "Reference" "PC542_P1_3"
			(at 0 0 90)
			(layer "B.SilkS")
			(hide yes)
			(effects
				(font
					(size 1.27 1.27)
				)
				(justify mirror)
			)
		)
		(property "Value" ""
			(at 0 0 90)
			(layer "B.Fab")
			(effects
				(font
					(size 1.27 1.27)
				)
				(justify mirror)
			)
		)
		(duplicate_pad_numbers_are_jumpers no)
		(fp_line
			(start -1.524 0.762)
			(end 1.524 0.762)
			(stroke
				(width 0.1524)
				(type default)
			)
			(layer "B.SilkS")
		)
		(fp_line
			(start 1.524 0.762)
			(end 1.524 -0.762)
			(stroke
				(width 0.1524)
				(type default)
			)
			(layer "B.SilkS")
		)
		(fp_line
			(start -1.524 -0.762)
			(end -1.524 0.762)
			(stroke
				(width 0.1524)
				(type default)
			)
			(layer "B.SilkS")
		)
		(fp_line
			(start 1.524 -0.762)
			(end -1.524 -0.762)
			(stroke
				(width 0.1524)
				(type default)
			)
			(layer "B.SilkS")
		)
		(fp_line
			(start -1.1049 0.724916)
			(end -1.1049 -0.724916)
			(stroke
				(width 0.1)
				(type default)
			)
			(layer "B.Fab")
		)
		(fp_line
			(start 1.1049 0.724916)
			(end -1.1049 0.724916)
			(stroke
				(width 0.1)
				(type default)
			)
			(layer "B.Fab")
		)
		(fp_line
			(start -1.1049 -0.724916)
			(end 1.1049 -0.724916)
			(stroke
				(width 0.1)
				(type default)
			)
			(layer "B.Fab")
		)
		(fp_line
			(start 1.1049 -0.724916)
			(end 1.1049 0.724916)
			(stroke
				(width 0.1)
				(type default)
			)
			(layer "B.Fab")
		)
		(pad "1" smd rect
			(at 0.889 0 270)
			(size 1.016 1.27)
			(layers "B.Cu" "B.Mask" "B.Paste")
			(net "PVCCIN_CPU1")
		)
		(pad "2" smd rect
			(at -0.889 0 270)
			(size 1.016 1.27)
			(layers "B.Cu" "B.Mask" "B.Paste")
			(net "GND")
		)
	)
	(footprint ""
		(layer "B.Cu")
		(at 155.074112 -38.579552 180)
		(property "Reference" "C2320"
			(at 0 0 0)
			(layer "B.SilkS")
			(hide yes)
			(effects
				(font
					(size 1.27 1.27)
				)
				(justify mirror)
			)
		)
		(property "Value" ""
			(at 0 0 0)
			(layer "B.Fab")
			(effects
				(font
					(size 1.27 1.27)
				)
				(justify mirror)
			)
		)
		(duplicate_pad_numbers_are_jumpers no)
		(fp_line
			(start 0.7874 0.4064)
			(end 0.7874 -0.4064)
			(stroke
				(width 0.1524)
				(type default)
			)
			(layer "B.SilkS")
		)
		(fp_line
			(start 0.7874 -0.4064)
			(end -0.7874 -0.4064)
			(stroke
				(width 0.1524)
				(type default)
			)
			(layer "B.SilkS")
		)
		(fp_line
			(start -0.7874 0.4064)
			(end 0.7874 0.4064)
			(stroke
				(width 0.1524)
				(type default)
			)
			(layer "B.SilkS")
		)
		(fp_line
			(start -0.7874 -0.4064)
			(end -0.7874 0.4064)
			(stroke
				(width 0.1524)
				(type default)
			)
			(layer "B.SilkS")
		)
		(fp_line
			(start 0.67945 0.3048)
			(end 0.67945 -0.305054)
			(stroke
				(width 0.1)
				(type default)
			)
			(layer "B.Fab")
		)
		(fp_line
			(start 0.67945 -0.305054)
			(end 0.12065 -0.305054)
			(stroke
				(width 0.1)
				(type default)
			)
			(layer "B.Fab")
		)
		(fp_line
			(start 0.12065 0.3048)
			(end 0.67945 0.3048)
			(stroke
				(width 0.1)
				(type default)
			)
			(layer "B.Fab")
		)
		(fp_line
			(start 0.12065 0.2794)
			(end 0.12065 0.3048)
			(stroke
				(width 0.1)
				(type default)
			)
			(layer "B.Fab")
		)
		(fp_line
			(start 0.12065 -0.2794)
			(end -0.12065 -0.2794)
			(stroke
				(width 0.1)
				(type default)
			)
			(layer "B.Fab")
		)
		(fp_line
			(start 0.12065 -0.305054)
			(end 0.12065 -0.2794)
			(stroke
				(width 0.1)
				(type default)
			)
			(layer "B.Fab")
		)
		(fp_line
			(start -0.120396 0.3048)
			(end -0.120396 0.2794)
			(stroke
				(width 0.1)
				(type default)
			)
			(layer "B.Fab")
		)
		(fp_line
			(start -0.120396 0.2794)
			(end 0.12065 0.2794)
			(stroke
				(width 0.1)
				(type default)
			)
			(layer "B.Fab")
		)
		(fp_line
			(start -0.12065 -0.2794)
			(end -0.12065 -0.3048)
			(stroke
				(width 0.1)
				(type default)
			)
			(layer "B.Fab")
		)
		(fp_line
			(start -0.12065 -0.3048)
			(end -0.67945 -0.3048)
			(stroke
				(width 0.1)
				(type default)
			)
			(layer "B.Fab")
		)
		(fp_line
			(start -0.67945 0.3048)
			(end -0.120396 0.3048)
			(stroke
				(width 0.1)
				(type default)
			)
			(layer "B.Fab")
		)
		(fp_line
			(start -0.67945 -0.3048)
			(end -0.67945 0.3048)
			(stroke
				(width 0.1)
				(type default)
			)
			(layer "B.Fab")
		)
		(pad "1" smd circle
			(at 0.40005 0)
			(size 0 0)
			(layers "B.Cu" "B.Mask" "B.Paste")
			(net "P3V3_AUX_USB_HUB_2")
		)
		(pad "2" smd circle
			(at -0.40005 0)
			(size 0 0)
			(layers "B.Cu" "B.Mask" "B.Paste")
			(net "GND")
		)
	)
)
